(kicad_pcb
	(version 20260206)
	(generator "pcbnew")
	(generator_version "10.0")
	(general
		(thickness 1.6)
		(legacy_teardrops no)
	)
	(paper "A4")
	(title_block
		(title "04192023_DAF0TMB3IC0_F0TG_MB_C_brd_V02_OCP.brd")
		(comment 1 "Grand Teton / footprints 3820-3826 of 8354")
	)
	(layers
		(0 "F.Cu" signal "TOP")
		(4 "In1.Cu" signal "GND")
		(6 "In2.Cu" signal "IN1")
		(8 "In3.Cu" signal "GND1")
		(10 "In4.Cu" signal "IN2")
		(12 "In5.Cu" signal "GND2")
		(14 "In6.Cu" signal "IN3")
		(16 "In7.Cu" signal "GND3")
		(18 "In8.Cu" signal "VCC")
		(20 "In9.Cu" signal "VCC1")
		(22 "In10.Cu" signal "GND4")
		(24 "In11.Cu" signal "IN4")
		(26 "In12.Cu" signal "GND5")
		(28 "In13.Cu" signal "IN5")
		(30 "In14.Cu" signal "GND6")
		(32 "In15.Cu" signal "IN6")
		(34 "In16.Cu" signal "GND7")
		(2 "B.Cu" signal "BOTTOM")
		(9 "F.Adhes" user "F.Adhesive")
		(11 "B.Adhes" user "B.Adhesive")
		(13 "F.Paste" user "Package Geometry/Pastemask Top")
		(15 "B.Paste" user "Package Geometry/Pastemask Bottom")
		(5 "F.SilkS" user "Ref Des/Silkscreen Top")
		(7 "B.SilkS" user "Ref Des/Silkscreen Bottom")
		(1 "F.Mask" user "Board Geometry/Soldermask Top")
		(3 "B.Mask" user "Board Geometry/Soldermask Bottom")
		(17 "Dwgs.User" user "User.Drawings")
		(19 "Cmts.User" user "User.Comments")
		(21 "Eco1.User" user "User.Eco1")
		(23 "Eco2.User" user "User.Eco2")
		(25 "Edge.Cuts" user "Board Geometry/Outline")
		(27 "Margin" user)
		(31 "F.CrtYd" user "Package Geometry/Place Bound Top")
		(29 "B.CrtYd" user "Package Geometry/Place Bound Bottom")
		(35 "F.Fab" user "Ref Des/Assembly Top")
		(33 "B.Fab" user "Ref Des/Assembly Bottom")
	)
	(footprint ""
		(layer "F.Cu")
		(at 452.995792 -53.075078 90)
		(property "Reference" "PC577"
			(at 0 0 90)
			(layer "F.SilkS")
			(hide yes)
			(effects
				(font
					(size 1.27 1.27)
				)
			)
		)
		(property "Value" ""
			(at 0 0 90)
			(layer "F.Fab")
			(effects
				(font
					(size 1.27 1.27)
				)
			)
		)
		(duplicate_pad_numbers_are_jumpers no)
		(fp_line
			(start 0.7874 -0.4064)
			(end 0.7874 0.4064)
			(stroke
				(width 0.1524)
				(type default)
			)
			(layer "F.SilkS")
		)
		(fp_line
			(start -0.7874 -0.4064)
			(end 0.7874 -0.4064)
			(stroke
				(width 0.1524)
				(type default)
			)
			(layer "F.SilkS")
		)
		(fp_line
			(start 0.7874 0.4064)
			(end -0.7874 0.4064)
			(stroke
				(width 0.1524)
				(type default)
			)
			(layer "F.SilkS")
		)
		(fp_line
			(start -0.7874 0.4064)
			(end -0.7874 -0.4064)
			(stroke
				(width 0.1524)
				(type default)
			)
			(layer "F.SilkS")
		)
		(fp_line
			(start -0.12065 -0.305054)
			(end -0.12065 -0.2794)
			(stroke
				(width 0.1)
				(type default)
			)
			(layer "F.Fab")
		)
		(fp_line
			(start -0.67945 -0.305054)
			(end -0.12065 -0.305054)
			(stroke
				(width 0.1)
				(type default)
			)
			(layer "F.Fab")
		)
		(fp_line
			(start 0.67945 -0.3048)
			(end 0.67945 0.3048)
			(stroke
				(width 0.1)
				(type default)
			)
			(layer "F.Fab")
		)
		(fp_line
			(start 0.12065 -0.3048)
			(end 0.67945 -0.3048)
			(stroke
				(width 0.1)
				(type default)
			)
			(layer "F.Fab")
		)
		(fp_line
			(start 0.12065 -0.2794)
			(end 0.12065 -0.3048)
			(stroke
				(width 0.1)
				(type default)
			)
			(layer "F.Fab")
		)
		(fp_line
			(start -0.12065 -0.2794)
			(end 0.12065 -0.2794)
			(stroke
				(width 0.1)
				(type default)
			)
			(layer "F.Fab")
		)
		(fp_line
			(start 0.120396 0.2794)
			(end -0.12065 0.2794)
			(stroke
				(width 0.1)
				(type default)
			)
			(layer "F.Fab")
		)
		(fp_line
			(start -0.12065 0.2794)
			(end -0.12065 0.3048)
			(stroke
				(width 0.1)
				(type default)
			)
			(layer "F.Fab")
		)
		(fp_line
			(start 0.67945 0.3048)
			(end 0.120396 0.3048)
			(stroke
				(width 0.1)
				(type default)
			)
			(layer "F.Fab")
		)
		(fp_line
			(start 0.120396 0.3048)
			(end 0.120396 0.2794)
			(stroke
				(width 0.1)
				(type default)
			)
			(layer "F.Fab")
		)
		(fp_line
			(start -0.12065 0.3048)
			(end -0.67945 0.3048)
			(stroke
				(width 0.1)
				(type default)
			)
			(layer "F.Fab")
		)
		(fp_line
			(start -0.67945 0.3048)
			(end -0.67945 -0.305054)
			(stroke
				(width 0.1)
				(type default)
			)
			(layer "F.Fab")
		)
		(pad "1" smd circle
			(at -0.40005 0 90)
			(size 0 0)
			(layers "F.Cu" "F.Mask" "F.Paste")
			(net "SW_P3V3_AUX_FLT")
		)
		(pad "2" smd circle
			(at 0.40005 0 90)
			(size 0 0)
			(layers "F.Cu" "F.Mask" "F.Paste")
			(net "GND")
		)
	)
	(footprint ""
		(layer "F.Cu")
		(at 179.705 -100.294948 90)
		(property "Reference" "R190"
			(at 0 0 90)
			(layer "F.SilkS")
			(hide yes)
			(effects
				(font
					(size 1.27 1.27)
				)
			)
		)
		(property "Value" ""
			(at 0 0 90)
			(layer "F.Fab")
			(effects
				(font
					(size 1.27 1.27)
				)
			)
		)
		(duplicate_pad_numbers_are_jumpers no)
		(fp_line
			(start 0.7874 -0.4064)
			(end 0.7874 0.4064)
			(stroke
				(width 0.1524)
				(type default)
			)
			(layer "F.SilkS")
		)
		(fp_line
			(start -0.7874 -0.4064)
			(end 0.7874 -0.4064)
			(stroke
				(width 0.1524)
				(type default)
			)
			(layer "F.SilkS")
		)
		(fp_line
			(start 0.7874 0.4064)
			(end -0.7874 0.4064)
			(stroke
				(width 0.1524)
				(type default)
			)
			(layer "F.SilkS")
		)
		(fp_line
			(start -0.7874 0.4064)
			(end -0.7874 -0.4064)
			(stroke
				(width 0.1524)
				(type default)
			)
			(layer "F.SilkS")
		)
		(fp_line
			(start -0.12065 -0.305054)
			(end -0.12065 -0.2794)
			(stroke
				(width 0.1)
				(type default)
			)
			(layer "F.Fab")
		)
		(fp_line
			(start -0.67945 -0.305054)
			(end -0.12065 -0.305054)
			(stroke
				(width 0.1)
				(type default)
			)
			(layer "F.Fab")
		)
		(fp_line
			(start 0.67945 -0.3048)
			(end 0.67945 0.3048)
			(stroke
				(width 0.1)
				(type default)
			)
			(layer "F.Fab")
		)
		(fp_line
			(start 0.12065 -0.3048)
			(end 0.67945 -0.3048)
			(stroke
				(width 0.1)
				(type default)
			)
			(layer "F.Fab")
		)
		(fp_line
			(start 0.12065 -0.2794)
			(end 0.12065 -0.3048)
			(stroke
				(width 0.1)
				(type default)
			)
			(layer "F.Fab")
		)
		(fp_line
			(start -0.12065 -0.2794)
			(end 0.12065 -0.2794)
			(stroke
				(width 0.1)
				(type default)
			)
			(layer "F.Fab")
		)
		(fp_line
			(start 0.120396 0.2794)
			(end -0.12065 0.2794)
			(stroke
				(width 0.1)
				(type default)
			)
			(layer "F.Fab")
		)
		(fp_line
			(start -0.12065 0.2794)
			(end -0.12065 0.3048)
			(stroke
				(width 0.1)
				(type default)
			)
			(layer "F.Fab")
		)
		(fp_line
			(start 0.67945 0.3048)
			(end 0.120396 0.3048)
			(stroke
				(width 0.1)
				(type default)
			)
			(layer "F.Fab")
		)
		(fp_line
			(start 0.120396 0.3048)
			(end 0.120396 0.2794)
			(stroke
				(width 0.1)
				(type default)
			)
			(layer "F.Fab")
		)
		(fp_line
			(start -0.12065 0.3048)
			(end -0.67945 0.3048)
			(stroke
				(width 0.1)
				(type default)
			)
			(layer "F.Fab")
		)
		(fp_line
			(start -0.67945 0.3048)
			(end -0.67945 -0.305054)
			(stroke
				(width 0.1)
				(type default)
			)
			(layer "F.Fab")
		)
		(pad "1" smd circle
			(at -0.40005 0 90)
			(size 0 0)
			(layers "F.Cu" "F.Mask" "F.Paste")
			(net "FM_CPU1_BMC_RST_N")
		)
		(pad "2" smd circle
			(at 0.40005 0 90)
			(size 0 0)
			(layers "F.Cu" "F.Mask" "F.Paste")
			(net "FM_CPU1_BMC_RST_R_N")
		)
	)
	(footprint ""
		(layer "F.Cu")
		(at 365.887 -411.226 -90)
		(property "Reference" "R6253"
			(at 0 0 270)
			(layer "F.SilkS")
			(hide yes)
			(effects
				(font
					(size 1.27 1.27)
				)
			)
		)
		(property "Value" ""
			(at 0 0 270)
			(layer "F.Fab")
			(effects
				(font
					(size 1.27 1.27)
				)
			)
		)
		(duplicate_pad_numbers_are_jumpers no)
		(fp_line
			(start -0.7874 0.4064)
			(end -0.7874 -0.4064)
			(stroke
				(width 0.1524)
				(type default)
			)
			(layer "F.SilkS")
		)
		(fp_line
			(start 0.7874 0.4064)
			(end -0.7874 0.4064)
			(stroke
				(width 0.1524)
				(type default)
			)
			(layer "F.SilkS")
		)
		(fp_line
			(start -0.7874 -0.4064)
			(end 0.7874 -0.4064)
			(stroke
				(width 0.1524)
				(type default)
			)
			(layer "F.SilkS")
		)
		(fp_line
			(start 0.7874 -0.4064)
			(end 0.7874 0.4064)
			(stroke
				(width 0.1524)
				(type default)
			)
			(layer "F.SilkS")
		)
		(fp_line
			(start -0.67945 0.3048)
			(end -0.67945 -0.305054)
			(stroke
				(width 0.1)
				(type default)
			)
			(layer "F.Fab")
		)
		(fp_line
			(start -0.12065 0.3048)
			(end -0.67945 0.3048)
			(stroke
				(width 0.1)
				(type default)
			)
			(layer "F.Fab")
		)
		(fp_line
			(start 0.120396 0.3048)
			(end 0.120396 0.2794)
			(stroke
				(width 0.1)
				(type default)
			)
			(layer "F.Fab")
		)
		(fp_line
			(start 0.67945 0.3048)
			(end 0.120396 0.3048)
			(stroke
				(width 0.1)
				(type default)
			)
			(layer "F.Fab")
		)
		(fp_line
			(start -0.12065 0.2794)
			(end -0.12065 0.3048)
			(stroke
				(width 0.1)
				(type default)
			)
			(layer "F.Fab")
		)
		(fp_line
			(start 0.120396 0.2794)
			(end -0.12065 0.2794)
			(stroke
				(width 0.1)
				(type default)
			)
			(layer "F.Fab")
		)
		(fp_line
			(start -0.12065 -0.2794)
			(end 0.12065 -0.2794)
			(stroke
				(width 0.1)
				(type default)
			)
			(layer "F.Fab")
		)
		(fp_line
			(start 0.12065 -0.2794)
			(end 0.12065 -0.3048)
			(stroke
				(width 0.1)
				(type default)
			)
			(layer "F.Fab")
		)
		(fp_line
			(start 0.12065 -0.3048)
			(end 0.67945 -0.3048)
			(stroke
				(width 0.1)
				(type default)
			)
			(layer "F.Fab")
		)
		(fp_line
			(start 0.67945 -0.3048)
			(end 0.67945 0.3048)
			(stroke
				(width 0.1)
				(type default)
			)
			(layer "F.Fab")
		)
		(fp_line
			(start -0.67945 -0.305054)
			(end -0.12065 -0.305054)
			(stroke
				(width 0.1)
				(type default)
			)
			(layer "F.Fab")
		)
		(fp_line
			(start -0.12065 -0.305054)
			(end -0.12065 -0.2794)
			(stroke
				(width 0.1)
				(type default)
			)
			(layer "F.Fab")
		)
		(pad "1" smd circle
			(at -0.40005 0 270)
			(size 0 0)
			(layers "F.Cu" "F.Mask" "F.Paste")
			(net "SMB_LM75_0_3V3AUX_SDA")
		)
		(pad "2" smd circle
			(at 0.40005 0 270)
			(size 0 0)
			(layers "F.Cu" "F.Mask" "F.Paste")
			(net "SMB_HSC_TYPE_ADC_SDA")
		)
	)
	(footprint ""
		(layer "F.Cu")
		(at 121.411238 -41.17975 -90)
		(property "Reference" "R6258"
			(at 0 0 270)
			(layer "F.SilkS")
			(hide yes)
			(effects
				(font
					(size 1.27 1.27)
				)
			)
		)
		(property "Value" ""
			(at 0 0 270)
			(layer "F.Fab")
			(effects
				(font
					(size 1.27 1.27)
				)
			)
		)
		(duplicate_pad_numbers_are_jumpers no)
		(fp_line
			(start -0.7874 0.4064)
			(end -0.7874 -0.4064)
			(stroke
				(width 0.1524)
				(type default)
			)
			(layer "F.SilkS")
		)
		(fp_line
			(start 0.7874 0.4064)
			(end -0.7874 0.4064)
			(stroke
				(width 0.1524)
				(type default)
			)
			(layer "F.SilkS")
		)
		(fp_line
			(start -0.7874 -0.4064)
			(end 0.7874 -0.4064)
			(stroke
				(width 0.1524)
				(type default)
			)
			(layer "F.SilkS")
		)
		(fp_line
			(start 0.7874 -0.4064)
			(end 0.7874 0.4064)
			(stroke
				(width 0.1524)
				(type default)
			)
			(layer "F.SilkS")
		)
		(fp_line
			(start -0.67945 0.3048)
			(end -0.67945 -0.305054)
			(stroke
				(width 0.1)
				(type default)
			)
			(layer "F.Fab")
		)
		(fp_line
			(start -0.12065 0.3048)
			(end -0.67945 0.3048)
			(stroke
				(width 0.1)
				(type default)
			)
			(layer "F.Fab")
		)
		(fp_line
			(start 0.120396 0.3048)
			(end 0.120396 0.2794)
			(stroke
				(width 0.1)
				(type default)
			)
			(layer "F.Fab")
		)
		(fp_line
			(start 0.67945 0.3048)
			(end 0.120396 0.3048)
			(stroke
				(width 0.1)
				(type default)
			)
			(layer "F.Fab")
		)
		(fp_line
			(start -0.12065 0.2794)
			(end -0.12065 0.3048)
			(stroke
				(width 0.1)
				(type default)
			)
			(layer "F.Fab")
		)
		(fp_line
			(start 0.120396 0.2794)
			(end -0.12065 0.2794)
			(stroke
				(width 0.1)
				(type default)
			)
			(layer "F.Fab")
		)
		(fp_line
			(start -0.12065 -0.2794)
			(end 0.12065 -0.2794)
			(stroke
				(width 0.1)
				(type default)
			)
			(layer "F.Fab")
		)
		(fp_line
			(start 0.12065 -0.2794)
			(end 0.12065 -0.3048)
			(stroke
				(width 0.1)
				(type default)
			)
			(layer "F.Fab")
		)
		(fp_line
			(start 0.12065 -0.3048)
			(end 0.67945 -0.3048)
			(stroke
				(width 0.1)
				(type default)
			)
			(layer "F.Fab")
		)
		(fp_line
			(start 0.67945 -0.3048)
			(end 0.67945 0.3048)
			(stroke
				(width 0.1)
				(type default)
			)
			(layer "F.Fab")
		)
		(fp_line
			(start -0.67945 -0.305054)
			(end -0.12065 -0.305054)
			(stroke
				(width 0.1)
				(type default)
			)
			(layer "F.Fab")
		)
		(fp_line
			(start -0.12065 -0.305054)
			(end -0.12065 -0.2794)
			(stroke
				(width 0.1)
				(type default)
			)
			(layer "F.Fab")
		)
		(pad "1" smd circle
			(at -0.40005 0 270)
			(size 0 0)
			(layers "F.Cu" "F.Mask" "F.Paste")
			(net "P3V3_AUX")
		)
		(pad "2" smd circle
			(at 0.40005 0 270)
			(size 0 0)
			(layers "F.Cu" "F.Mask" "F.Paste")
			(net "USB_HUB2_TI_PWRCTL2_MRP_VDD12")
		)
	)
	(footprint ""
		(layer "F.Cu")
		(at 302.271938 -119.479568 180)
		(property "Reference" "R722"
			(at 0 0 180)
			(layer "F.SilkS")
			(hide yes)
			(effects
				(font
					(size 1.27 1.27)
				)
			)
		)
		(property "Value" ""
			(at 0 0 180)
			(layer "F.Fab")
			(effects
				(font
					(size 1.27 1.27)
				)
			)
		)
		(duplicate_pad_numbers_are_jumpers no)
		(fp_line
			(start 0.7874 0.4064)
			(end -0.7874 0.4064)
			(stroke
				(width 0.1524)
				(type default)
			)
			(layer "F.SilkS")
		)
		(fp_line
			(start 0.7874 -0.4064)
			(end 0.7874 0.4064)
			(stroke
				(width 0.1524)
				(type default)
			)
			(layer "F.SilkS")
		)
		(fp_line
			(start -0.7874 0.4064)
			(end -0.7874 -0.4064)
			(stroke
				(width 0.1524)
				(type default)
			)
			(layer "F.SilkS")
		)
		(fp_line
			(start -0.7874 -0.4064)
			(end 0.7874 -0.4064)
			(stroke
				(width 0.1524)
				(type default)
			)
			(layer "F.SilkS")
		)
		(fp_line
			(start 0.67945 0.3048)
			(end 0.120396 0.3048)
			(stroke
				(width 0.1)
				(type default)
			)
			(layer "F.Fab")
		)
		(fp_line
			(start 0.67945 -0.3048)
			(end 0.67945 0.3048)
			(stroke
				(width 0.1)
				(type default)
			)
			(layer "F.Fab")
		)
		(fp_line
			(start 0.12065 -0.2794)
			(end 0.12065 -0.3048)
			(stroke
				(width 0.1)
				(type default)
			)
			(layer "F.Fab")
		)
		(fp_line
			(start 0.12065 -0.3048)
			(end 0.67945 -0.3048)
			(stroke
				(width 0.1)
				(type default)
			)
			(layer "F.Fab")
		)
		(fp_line
			(start 0.120396 0.3048)
			(end 0.120396 0.2794)
			(stroke
				(width 0.1)
				(type default)
			)
			(layer "F.Fab")
		)
		(fp_line
			(start 0.120396 0.2794)
			(end -0.12065 0.2794)
			(stroke
				(width 0.1)
				(type default)
			)
			(layer "F.Fab")
		)
		(fp_line
			(start -0.12065 0.3048)
			(end -0.67945 0.3048)
			(stroke
				(width 0.1)
				(type default)
			)
			(layer "F.Fab")
		)
		(fp_line
			(start -0.12065 0.2794)
			(end -0.12065 0.3048)
			(stroke
				(width 0.1)
				(type default)
			)
			(layer "F.Fab")
		)
		(fp_line
			(start -0.12065 -0.2794)
			(end 0.12065 -0.2794)
			(stroke
				(width 0.1)
				(type default)
			)
			(layer "F.Fab")
		)
		(fp_line
			(start -0.12065 -0.305054)
			(end -0.12065 -0.2794)
			(stroke
				(width 0.1)
				(type default)
			)
			(layer "F.Fab")
		)
		(fp_line
			(start -0.67945 0.3048)
			(end -0.67945 -0.305054)
			(stroke
				(width 0.1)
				(type default)
			)
			(layer "F.Fab")
		)
		(fp_line
			(start -0.67945 -0.305054)
			(end -0.12065 -0.305054)
			(stroke
				(width 0.1)
				(type default)
			)
			(layer "F.Fab")
		)
		(pad "1" smd circle
			(at -0.40005 0 180)
			(size 0 0)
			(layers "F.Cu" "F.Mask" "F.Paste")
			(net "MB_FRU_ADDR0")
		)
		(pad "2" smd circle
			(at 0.40005 0 180)
			(size 0 0)
			(layers "F.Cu" "F.Mask" "F.Paste")
			(net "GND")
		)
	)
	(footprint ""
		(layer "F.Cu")
		(at 40.960294 -17.623536 90)
		(property "Reference" "C696"
			(at 0 0 90)
			(layer "F.SilkS")
			(hide yes)
			(effects
				(font
					(size 1.27 1.27)
				)
			)
		)
		(property "Value" ""
			(at 0 0 90)
			(layer "F.Fab")
			(effects
				(font
					(size 1.27 1.27)
				)
			)
		)
		(duplicate_pad_numbers_are_jumpers no)
		(fp_line
			(start 0.299974 -0.150114)
			(end 0.299974 0.150114)
			(stroke
				(width 0.1)
				(type default)
			)
			(layer "F.Fab")
		)
		(fp_line
			(start -0.299974 -0.150114)
			(end 0.299974 -0.150114)
			(stroke
				(width 0.1)
				(type default)
			)
			(layer "F.Fab")
		)
		(fp_line
			(start 0.299974 0.150114)
			(end -0.299974 0.150114)
			(stroke
				(width 0.1)
				(type default)
			)
			(layer "F.Fab")
		)
		(fp_line
			(start -0.299974 0.150114)
			(end -0.299974 -0.150114)
			(stroke
				(width 0.1)
				(type default)
			)
			(layer "F.Fab")
		)
		(pad "1" smd rect
			(at -0.2667 0 90)
			(size 0.3048 0.381)
			(layers "F.Cu" "F.Mask" "F.Paste")
			(net "P5E_CPU1_G1_TX_C_DN<6>")
		)
		(pad "2" smd rect
			(at 0.2667 0 90)
			(size 0.3048 0.381)
			(layers "F.Cu" "F.Mask" "F.Paste")
			(net "P5E_CPU1_G1_TX_DN<6>")
		)
	)
	(footprint ""
		(layer "F.Cu")
		(at 325.39686 -340.199726)
		(property "Reference" "PR77"
			(at 0 0 0)
			(layer "F.SilkS")
			(hide yes)
			(effects
				(font
					(size 1.27 1.27)
				)
			)
		)
		(property "Value" ""
			(at 0 0 0)
			(layer "F.Fab")
			(effects
				(font
					(size 1.27 1.27)
				)
			)
		)
		(duplicate_pad_numbers_are_jumpers no)
		(fp_line
			(start -0.7874 -0.4064)
			(end 0.7874 -0.4064)
			(stroke
				(width 0.1524)
				(type default)
			)
			(layer "F.SilkS")
		)
		(fp_line
			(start -0.7874 0.4064)
			(end -0.7874 -0.4064)
			(stroke
				(width 0.1524)
				(type default)
			)
			(layer "F.SilkS")
		)
		(fp_line
			(start 0.7874 -0.4064)
			(end 0.7874 0.4064)
			(stroke
				(width 0.1524)
				(type default)
			)
			(layer "F.SilkS")
		)
		(fp_line
			(start 0.7874 0.4064)
			(end -0.7874 0.4064)
			(stroke
				(width 0.1524)
				(type default)
			)
			(layer "F.SilkS")
		)
		(fp_line
			(start -0.67945 -0.305054)
			(end -0.12065 -0.305054)
			(stroke
				(width 0.1)
				(type default)
			)
			(layer "F.Fab")
		)
		(fp_line
			(start -0.67945 0.3048)
			(end -0.67945 -0.305054)
			(stroke
				(width 0.1)
				(type default)
			)
			(layer "F.Fab")
		)
		(fp_line
			(start -0.12065 -0.305054)
			(end -0.12065 -0.2794)
			(stroke
				(width 0.1)
				(type default)
			)
			(layer "F.Fab")
		)
		(fp_line
			(start -0.12065 -0.2794)
			(end 0.12065 -0.2794)
			(stroke
				(width 0.1)
				(type default)
			)
			(layer "F.Fab")
		)
		(fp_line
			(start -0.12065 0.2794)
			(end -0.12065 0.3048)
			(stroke
				(width 0.1)
				(type default)
			)
			(layer "F.Fab")
		)
		(fp_line
			(start -0.12065 0.3048)
			(end -0.67945 0.3048)
			(stroke
				(width 0.1)
				(type default)
			)
			(layer "F.Fab")
		)
		(fp_line
			(start 0.120396 0.2794)
			(end -0.12065 0.2794)
			(stroke
				(width 0.1)
				(type default)
			)
			(layer "F.Fab")
		)
		(fp_line
			(start 0.120396 0.3048)
			(end 0.120396 0.2794)
			(stroke
				(width 0.1)
				(type default)
			)
			(layer "F.Fab")
		)
		(fp_line
			(start 0.12065 -0.3048)
			(end 0.67945 -0.3048)
			(stroke
				(width 0.1)
				(type default)
			)
			(layer "F.Fab")
		)
		(fp_line
			(start 0.12065 -0.2794)
			(end 0.12065 -0.3048)
			(stroke
				(width 0.1)
				(type default)
			)
			(layer "F.Fab")
		)
		(fp_line
			(start 0.67945 -0.3048)
			(end 0.67945 0.3048)
			(stroke
				(width 0.1)
				(type default)
			)
			(layer "F.Fab")
		)
		(fp_line
			(start 0.67945 0.3048)
			(end 0.120396 0.3048)
			(stroke
				(width 0.1)
				(type default)
			)
			(layer "F.Fab")
		)
		(pad "1" smd circle
			(at -0.40005 0)
			(size 0 0)
			(layers "F.Cu" "F.Mask" "F.Paste")
			(net "PVDDCR_CPU1_P0_LSET2")
		)
		(pad "2" smd circle
			(at 0.40005 0)
			(size 0 0)
			(layers "F.Cu" "F.Mask" "F.Paste")
			(net "GND")
		)
	)
)
